# S9S_MB_2U (Grand Teton) — schematic netlist excerpt (pin names and nets, part order shuffled) for the footprints in the layout excerpt that follows; sources: Cadence DE-HDL packaged netlist, KiCad conversion of 03242023_DA0F0TMBIJ0_F0T_Motherboard_J_brd_V01_OCP.brd

PC1342  Q_CAP  0.1UF 25V 10% X7R  pkg 0402  page 269 : A = GND ; B = PVCCIN_CPU0_VREF
R4455  Q_RES  0 5% EMPTY  pkg 0402LF  page 196 : A = USB2_HUB_2_EXT_DN ; B = USB2_HUB_2_BUF_EXT_R_DN

(kicad_pcb
	(version 20260206)
	(generator "pcbnew")
	(generator_version "10.0")
	(general
		(thickness 1.6)
		(legacy_teardrops no)
	)
	(paper "A4")
	(title_block
		(title "03242023_DA0F0TMBIJ0_F0T_Motherboard_J_brd_V01_OCP.brd")
		(comment 1 "Grand Teton / footprints 1328-1329 of 6105")
	)
	(layers
		(0 "F.Cu" signal "TOP")
		(4 "In1.Cu" signal "GND")
		(6 "In2.Cu" signal "IN1")
		(8 "In3.Cu" signal "GND1")
		(10 "In4.Cu" signal "IN2")
		(12 "In5.Cu" signal "GND2")
		(14 "In6.Cu" signal "IN3")
		(16 "In7.Cu" signal "GND3")
		(18 "In8.Cu" signal "VCC")
		(20 "In9.Cu" signal "VCC1")
		(22 "In10.Cu" signal "GND4")
		(24 "In11.Cu" signal "IN4")
		(26 "In12.Cu" signal "GND5")
		(28 "In13.Cu" signal "IN5")
		(30 "In14.Cu" signal "GND6")
		(32 "In15.Cu" signal "IN6")
		(34 "In16.Cu" signal "GND7")
		(2 "B.Cu" signal "BOTTOM")
		(9 "F.Adhes" user "F.Adhesive")
		(11 "B.Adhes" user "B.Adhesive")
		(13 "F.Paste" user "Package Geometry/Pastemask Top")
		(15 "B.Paste" user "Package Geometry/Pastemask Bottom")
		(5 "F.SilkS" user "Ref Des/Silkscreen Top")
		(7 "B.SilkS" user "Ref Des/Silkscreen Bottom")
		(1 "F.Mask" user "Board Geometry/Soldermask Top")
		(3 "B.Mask" user "Board Geometry/Soldermask Bottom")
		(17 "Dwgs.User" user "User.Drawings")
		(19 "Cmts.User" user "User.Comments")
		(21 "Eco1.User" user "User.Eco1")
		(23 "Eco2.User" user "User.Eco2")
		(25 "Edge.Cuts" user "Board Geometry/Outline")
		(27 "Margin" user)
		(31 "F.CrtYd" user "Package Geometry/Place Bound Top")
		(29 "B.CrtYd" user "Package Geometry/Place Bound Bottom")
		(35 "F.Fab" user "Ref Des/Assembly Top")
		(33 "B.Fab" user "Ref Des/Assembly Bottom")
	)
	(footprint ""
		(layer "F.Cu")
		(at 157.061408 -44.662598 90)
		(property "Reference" "R4455"
			(at 0 0 90)
			(layer "F.SilkS")
			(hide yes)
			(effects
				(font
					(size 1.27 1.27)
				)
			)
		)
		(property "Value" ""
			(at 0 0 90)
			(layer "F.Fab")
			(effects
				(font
					(size 1.27 1.27)
				)
			)
		)
		(duplicate_pad_numbers_are_jumpers no)
		(fp_line
			(start 0.7874 -0.4064)
			(end 0.7874 0.4064)
			(stroke
				(width 0.1524)
				(type default)
			)
			(layer "F.SilkS")
		)
		(fp_line
			(start 0.7874 0.4064)
			(end -0.7874 0.4064)
			(stroke
				(width 0.1524)
				(type default)
			)
			(layer "F.SilkS")
		)
		(fp_line
			(start -0.12065 -0.305054)
			(end -0.12065 -0.2794)
			(stroke
				(width 0.1)
				(type default)
			)
			(layer "F.Fab")
		)
		(fp_line
			(start -0.67945 -0.305054)
			(end -0.12065 -0.305054)
			(stroke
				(width 0.1)
				(type default)
			)
			(layer "F.Fab")
		)
		(fp_line
			(start 0.67945 -0.3048)
			(end 0.67945 0.3048)
			(stroke
				(width 0.1)
				(type default)
			)
			(layer "F.Fab")
		)
		(fp_line
			(start 0.12065 -0.3048)
			(end 0.67945 -0.3048)
			(stroke
				(width 0.1)
				(type default)
			)
			(layer "F.Fab")
		)
		(fp_line
			(start 0.12065 -0.2794)
			(end 0.12065 -0.3048)
			(stroke
				(width 0.1)
				(type default)
			)
			(layer "F.Fab")
		)
		(fp_line
			(start -0.12065 -0.2794)
			(end 0.12065 -0.2794)
			(stroke
				(width 0.1)
				(type default)
			)
			(layer "F.Fab")
		)
		(fp_line
			(start 0.120396 0.2794)
			(end -0.12065 0.2794)
			(stroke
				(width 0.1)
				(type default)
			)
			(layer "F.Fab")
		)
		(fp_line
			(start -0.12065 0.2794)
			(end -0.12065 0.3048)
			(stroke
				(width 0.1)
				(type default)
			)
			(layer "F.Fab")
		)
		(fp_line
			(start 0.67945 0.3048)
			(end 0.120396 0.3048)
			(stroke
				(width 0.1)
				(type default)
			)
			(layer "F.Fab")
		)
		(fp_line
			(start 0.120396 0.3048)
			(end 0.120396 0.2794)
			(stroke
				(width 0.1)
				(type default)
			)
			(layer "F.Fab")
		)
		(fp_line
			(start -0.12065 0.3048)
			(end -0.67945 0.3048)
			(stroke
				(width 0.1)
				(type default)
			)
			(layer "F.Fab")
		)
		(fp_line
			(start -0.67945 0.3048)
			(end -0.67945 -0.305054)
			(stroke
				(width 0.1)
				(type default)
			)
			(layer "F.Fab")
		)
		(pad "1" smd rect
			(at -0.40005 0 270)
			(size 0.4572 0.508)
			(layers "F.Cu" "F.Mask" "F.Paste")
			(net "USB2_HUB_2_EXT_DN")
		)
		(pad "2" smd rect
			(at 0.40005 0 270)
			(size 0.4572 0.508)
			(layers "F.Cu" "F.Mask" "F.Paste")
			(net "USB2_HUB_2_BUF_EXT_R_DN")
		)
	)
	(footprint ""
		(layer "F.Cu")
		(at 334.024732 -341.707978 -90)
		(property "Reference" "PC1342"
			(at 0 0 270)
			(layer "F.SilkS")
			(hide yes)
			(effects
				(font
					(size 1.27 1.27)
				)
			)
		)
		(property "Value" ""
			(at 0 0 270)
			(layer "F.Fab")
			(effects
				(font
					(size 1.27 1.27)
				)
			)
		)
		(duplicate_pad_numbers_are_jumpers no)
		(fp_line
			(start -0.7874 0.4064)
			(end -0.7874 -0.4064)
			(stroke
				(width 0.1524)
				(type default)
			)
			(layer "F.SilkS")
		)
		(fp_line
			(start 0.7874 0.4064)
			(end -0.7874 0.4064)
			(stroke
				(width 0.1524)
				(type default)
			)
			(layer "F.SilkS")
		)
		(fp_line
			(start -0.7874 -0.4064)
			(end 0.7874 -0.4064)
			(stroke
				(width 0.1524)
				(type default)
			)
			(layer "F.SilkS")
		)
		(fp_line
			(start 0.7874 -0.4064)
			(end 0.7874 0.4064)
			(stroke
				(width 0.1524)
				(type default)
			)
			(layer "F.SilkS")
		)
		(fp_line
			(start -0.67945 0.3048)
			(end -0.67945 -0.305054)
			(stroke
				(width 0.1)
				(type default)
			)
			(layer "F.Fab")
		)
		(fp_line
			(start -0.12065 0.3048)
			(end -0.67945 0.3048)
			(stroke
				(width 0.1)
				(type default)
			)
			(layer "F.Fab")
		)
		(fp_line
			(start 0.120396 0.3048)
			(end 0.120396 0.2794)
			(stroke
				(width 0.1)
				(type default)
			)
			(layer "F.Fab")
		)
		(fp_line
			(start 0.67945 0.3048)
			(end 0.120396 0.3048)
			(stroke
				(width 0.1)
				(type default)
			)
			(layer "F.Fab")
		)
		(fp_line
			(start -0.12065 0.2794)
			(end -0.12065 0.3048)
			(stroke
				(width 0.1)
				(type default)
			)
			(layer "F.Fab")
		)
		(fp_line
			(start 0.120396 0.2794)
			(end -0.12065 0.2794)
			(stroke
				(width 0.1)
				(type default)
			)
			(layer "F.Fab")
		)
		(fp_line
			(start -0.12065 -0.2794)
			(end 0.12065 -0.2794)
			(stroke
				(width 0.1)
				(type default)
			)
			(layer "F.Fab")
		)
		(fp_line
			(start 0.12065 -0.2794)
			(end 0.12065 -0.3048)
			(stroke
				(width 0.1)
				(type default)
			)
			(layer "F.Fab")
		)
		(fp_line
			(start 0.12065 -0.3048)
			(end 0.67945 -0.3048)
			(stroke
				(width 0.1)
				(type default)
			)
			(layer "F.Fab")
		)
		(fp_line
			(start 0.67945 -0.3048)
			(end 0.67945 0.3048)
			(stroke
				(width 0.1)
				(type default)
			)
			(layer "F.Fab")
		)
		(fp_line
			(start -0.67945 -0.305054)
			(end -0.12065 -0.305054)
			(stroke
				(width 0.1)
				(type default)
			)
			(layer "F.Fab")
		)
		(fp_line
			(start -0.12065 -0.305054)
			(end -0.12065 -0.2794)
			(stroke
				(width 0.1)
				(type default)
			)
			(layer "F.Fab")
		)
		(pad "1" smd circle
			(at -0.40005 0 270)
			(size 0 0)
			(layers "F.Cu" "F.Mask" "F.Paste")
			(net "GND")
		)
		(pad "2" smd circle
			(at 0.40005 0 270)
			(size 0 0)
			(layers "F.Cu" "F.Mask" "F.Paste")
			(net "PVCCIN_CPU0_VREF")
		)
	)
)
